# BASEBOARD_FAB2 (Tioga Pass) — schematic netlist excerpt (pin names and nets, part order shuffled) for the footprints in the layout excerpt that follows; sources: Cadence DE-HDL packaged netlist, KiCad conversion of Wiwynn_Tioga_Pass_MB.brd

R1E14  RES  68.1K 1% EMPTY  pkg 0402  page 207 : A = VR_PVCCIN_CPU1_PH1_OCSET ; B = GND
R25W72  RES  33.2 1% CHIP  pkg 0402  page 146 : A = LPC_LFRAME_N_CS0_N ; B = LPC_LFRAME_N_CS0_R_N
R1D33  RES  33.2 1% CHIP  pkg 0402  page 199 : A = PWRGD_P12V_R ; B = PWRGD_P12V_HSC

(kicad_pcb
	(version 20260206)
	(generator "pcbnew")
	(generator_version "10.0")
	(general
		(thickness 1.6)
		(legacy_teardrops no)
	)
	(paper "A4")
	(title_block
		(title "Wiwynn_Tioga_Pass_MB.brd")
		(comment 1 "Tioga Pass / footprints 1410-1412 of 4770")
	)
	(layers
		(0 "F.Cu" signal "TOP")
		(4 "In1.Cu" signal "L2GND")
		(6 "In2.Cu" signal "L3")
		(8 "In3.Cu" signal "L4GND")
		(10 "In4.Cu" signal "L5")
		(12 "In5.Cu" signal "L6GND")
		(14 "In6.Cu" signal "L7VCC")
		(16 "In7.Cu" signal "L8VCC")
		(18 "In8.Cu" signal "L9GND")
		(20 "In9.Cu" signal "L10")
		(22 "In10.Cu" signal "L11GND")
		(24 "In11.Cu" signal "L12")
		(26 "In12.Cu" signal "L13GND")
		(2 "B.Cu" signal "BOTTOM")
		(9 "F.Adhes" user "F.Adhesive")
		(11 "B.Adhes" user "B.Adhesive")
		(13 "F.Paste" user "Package Geometry/Pastemask Top")
		(15 "B.Paste" user "Package Geometry/Pastemask Bottom")
		(5 "F.SilkS" user "Ref Des/Silkscreen Top")
		(7 "B.SilkS" user "Ref Des/Silkscreen Bottom")
		(1 "F.Mask" user "Board Geometry/Soldermask Top")
		(3 "B.Mask" user "Board Geometry/Soldermask Bottom")
		(17 "Dwgs.User" user "User.Drawings")
		(19 "Cmts.User" user "User.Comments")
		(21 "Eco1.User" user "User.Eco1")
		(23 "Eco2.User" user "User.Eco2")
		(25 "Edge.Cuts" user "Board Geometry/Outline")
		(27 "Margin" user)
		(31 "F.CrtYd" user "Package Geometry/Place Bound Top")
		(29 "B.CrtYd" user "Package Geometry/Place Bound Bottom")
		(35 "F.Fab" user "Ref Des/Assembly Top")
		(33 "B.Fab" user "Ref Des/Assembly Bottom")
	)
	(footprint ""
		(layer "F.Cu")
		(at 12.9286 -75.8952)
		(property "Reference" "R1D33"
			(at 0 0 0)
			(layer "F.SilkS")
			(hide yes)
			(effects
				(font
					(size 1.27 1.27)
				)
			)
		)
		(property "Value" ""
			(at 0 0 0)
			(layer "F.Fab")
			(effects
				(font
					(size 1.27 1.27)
				)
			)
		)
		(duplicate_pad_numbers_are_jumpers no)
		(fp_poly
			(pts
				(xy -0.2794 -0.1016) (xy 0.2794 -0.1016) (xy 0.2794 0.9906) (xy -0.2794 0.9906)
			)
			(stroke
				(width 0)
				(type default)
			)
			(fill no)
			(layer "F.CrtYd")
		)
		(fp_line
			(start -0.2794 -0.1016)
			(end -0.2794 0.9906)
			(stroke
				(width 0.1)
				(type default)
			)
			(layer "F.Fab")
		)
		(fp_line
			(start -0.2794 0.9906)
			(end 0.2794 0.9906)
			(stroke
				(width 0.1)
				(type default)
			)
			(layer "F.Fab")
		)
		(fp_line
			(start 0.2794 -0.1016)
			(end -0.2794 -0.1016)
			(stroke
				(width 0.1)
				(type default)
			)
			(layer "F.Fab")
		)
		(fp_line
			(start 0.2794 0.9906)
			(end 0.2794 -0.1016)
			(stroke
				(width 0.1)
				(type default)
			)
			(layer "F.Fab")
		)
		(pad "1" smd rect
			(at 0 0)
			(size 0.508 0.508)
			(layers "F.Cu" "F.Mask" "F.Paste")
			(net "PWRGD_P12V_R")
		)
		(pad "2" smd rect
			(at 0 0.889)
			(size 0.508 0.508)
			(layers "F.Cu" "F.Mask" "F.Paste")
			(net "PWRGD_P12V_HSC")
		)
		(zone
			(layer "F.Cu")
			(hatch none 0.5)
			(connect_pads
				(clearance 0)
			)
			(min_thickness 0.25)
			(keepout
				(tracks allowed)
				(vias not_allowed)
				(pads allowed)
				(copperpour not_allowed)
				(footprints allowed)
			)
			(placement
				(enabled no)
				(sheetname "")
			)
			(fill
				(thermal_gap 0.5)
				(thermal_bridge_width 0.5)
				(island_removal_mode 0)
			)
			(polygon
				(pts
					(xy 12.6746 -75.6412) (xy 13.1826 -75.6412) (xy 13.1826 -75.2602) (xy 12.6746 -75.2602)
				)
			)
		)
		(zone
			(layer "F.Cu")
			(hatch none 0.5)
			(connect_pads
				(clearance 0)
			)
			(min_thickness 0.25)
			(keepout
				(tracks not_allowed)
				(vias allowed)
				(pads allowed)
				(copperpour not_allowed)
				(footprints allowed)
			)
			(placement
				(enabled no)
				(sheetname "")
			)
			(fill
				(thermal_gap 0.5)
				(thermal_bridge_width 0.5)
				(island_removal_mode 0)
			)
			(polygon
				(pts
					(xy 12.6746 -75.2602) (xy 13.1826 -75.2602) (xy 13.1826 -75.6412) (xy 12.6746 -75.6412)
				)
			)
		)
	)
	(footprint ""
		(layer "F.Cu")
		(at 27.990292 -55.771288 -90)
		(property "Reference" "R1E14"
			(at 0 0 270)
			(layer "F.SilkS")
			(hide yes)
			(effects
				(font
					(size 1.27 1.27)
				)
			)
		)
		(property "Value" ""
			(at 0 0 270)
			(layer "F.Fab")
			(effects
				(font
					(size 1.27 1.27)
				)
			)
		)
		(duplicate_pad_numbers_are_jumpers no)
		(fp_poly
			(pts
				(xy -0.2794 -0.1016) (xy 0.2794 -0.1016) (xy 0.2794 0.9906) (xy -0.2794 0.9906)
			)
			(stroke
				(width 0)
				(type default)
			)
			(fill no)
			(layer "F.CrtYd")
		)
		(fp_line
			(start -0.2794 0.9906)
			(end 0.2794 0.9906)
			(stroke
				(width 0.1)
				(type default)
			)
			(layer "F.Fab")
		)
		(fp_line
			(start 0.2794 0.9906)
			(end 0.2794 -0.1016)
			(stroke
				(width 0.1)
				(type default)
			)
			(layer "F.Fab")
		)
		(fp_line
			(start -0.2794 -0.1016)
			(end -0.2794 0.9906)
			(stroke
				(width 0.1)
				(type default)
			)
			(layer "F.Fab")
		)
		(fp_line
			(start 0.2794 -0.1016)
			(end -0.2794 -0.1016)
			(stroke
				(width 0.1)
				(type default)
			)
			(layer "F.Fab")
		)
		(pad "1" smd rect
			(at 0 0 270)
			(size 0.508 0.508)
			(layers "F.Cu" "F.Mask" "F.Paste")
			(net "VR_PVCCIN_CPU1_PH1_OCSET")
		)
		(pad "2" smd rect
			(at 0 0.889 270)
			(size 0.508 0.508)
			(layers "F.Cu" "F.Mask" "F.Paste")
			(net "GND")
		)
		(zone
			(layer "F.Cu")
			(hatch none 0.5)
			(connect_pads
				(clearance 0)
			)
			(min_thickness 0.25)
			(keepout
				(tracks not_allowed)
				(vias allowed)
				(pads allowed)
				(copperpour not_allowed)
				(footprints allowed)
			)
			(placement
				(enabled no)
				(sheetname "")
			)
			(fill
				(thermal_gap 0.5)
				(thermal_bridge_width 0.5)
				(island_removal_mode 0)
			)
			(polygon
				(pts
					(xy 27.355292 -56.025288) (xy 27.355292 -55.517288) (xy 27.736292 -55.517288) (xy 27.736292 -56.025288)
				)
			)
		)
		(zone
			(layer "F.Cu")
			(hatch none 0.5)
			(connect_pads
				(clearance 0)
			)
			(min_thickness 0.25)
			(keepout
				(tracks allowed)
				(vias not_allowed)
				(pads allowed)
				(copperpour not_allowed)
				(footprints allowed)
			)
			(placement
				(enabled no)
				(sheetname "")
			)
			(fill
				(thermal_gap 0.5)
				(thermal_bridge_width 0.5)
				(island_removal_mode 0)
			)
			(polygon
				(pts
					(xy 27.736292 -56.025288) (xy 27.736292 -55.517288) (xy 27.355292 -55.517288) (xy 27.355292 -56.025288)
				)
			)
		)
	)
	(footprint ""
		(layer "F.Cu")
		(at 379.7173 -90.551)
		(property "Reference" "R25W72"
			(at -0.8382 -0.67818 0)
			(unlocked yes)
			(layer "F.SilkS")
			(effects
				(font
					(size 0.4064 0.254)
					(thickness 0.1524)
				)
				(justify left)
			)
		)
		(property "Value" ""
			(at 0 0 0)
			(layer "F.Fab")
			(effects
				(font
					(size 1.27 1.27)
				)
			)
		)
		(duplicate_pad_numbers_are_jumpers no)
		(fp_poly
			(pts
				(xy -0.2794 -0.1016) (xy 0.2794 -0.1016) (xy 0.2794 0.9906) (xy -0.2794 0.9906)
			)
			(stroke
				(width 0)
				(type default)
			)
			(fill no)
			(layer "F.CrtYd")
		)
		(fp_line
			(start -0.2794 -0.1016)
			(end -0.2794 0.9906)
			(stroke
				(width 0.1)
				(type default)
			)
			(layer "F.Fab")
		)
		(fp_line
			(start -0.2794 0.9906)
			(end 0.2794 0.9906)
			(stroke
				(width 0.1)
				(type default)
			)
			(layer "F.Fab")
		)
		(fp_line
			(start 0.2794 -0.1016)
			(end -0.2794 -0.1016)
			(stroke
				(width 0.1)
				(type default)
			)
			(layer "F.Fab")
		)
		(fp_line
			(start 0.2794 0.9906)
			(end 0.2794 -0.1016)
			(stroke
				(width 0.1)
				(type default)
			)
			(layer "F.Fab")
		)
		(pad "1" smd rect
			(at 0 0)
			(size 0.508 0.508)
			(layers "F.Cu" "F.Mask" "F.Paste")
			(net "LPC_LFRAME_N_CS0_N")
		)
		(pad "2" smd rect
			(at 0 0.889)
			(size 0.508 0.508)
			(layers "F.Cu" "F.Mask" "F.Paste")
			(net "LPC_LFRAME_N_CS0_R_N")
		)
		(zone
			(layer "F.Cu")
			(hatch none 0.5)
			(connect_pads
				(clearance 0)
			)
			(min_thickness 0.25)
			(keepout
				(tracks allowed)
				(vias not_allowed)
				(pads allowed)
				(copperpour not_allowed)
				(footprints allowed)
			)
			(placement
				(enabled no)
				(sheetname "")
			)
			(fill
				(thermal_gap 0.5)
				(thermal_bridge_width 0.5)
				(island_removal_mode 0)
			)
			(polygon
				(pts
					(xy 379.4633 -90.297) (xy 379.9713 -90.297) (xy 379.9713 -89.916) (xy 379.4633 -89.916)
				)
			)
		)
		(zone
			(layer "F.Cu")
			(hatch none 0.5)
			(connect_pads
				(clearance 0)
			)
			(min_thickness 0.25)
			(keepout
				(tracks not_allowed)
				(vias allowed)
				(pads allowed)
				(copperpour not_allowed)
				(footprints allowed)
			)
			(placement
				(enabled no)
				(sheetname "")
			)
			(fill
				(thermal_gap 0.5)
				(thermal_bridge_width 0.5)
				(island_removal_mode 0)
			)
			(polygon
				(pts
					(xy 379.4633 -89.916) (xy 379.9713 -89.916) (xy 379.9713 -90.297) (xy 379.4633 -90.297)
				)
			)
		)
	)
)
